# TIMECARD (Time Appliance Project (Time Card)) — schematic netlist excerpt (pin names and nets, part order shuffled) for the footprints in the layout excerpt that follows; sources: Cadence DE-HDL packaged netlist, KiCad conversion of R4006-B0001-02_R01.brd

R319  RESISTOR  33OHM 1%  pkg SMC_0402R_H016  page 26 : \1\ = FPGA_OUT_RGB_LED_SHUTDOWN_N ; \2\ = RGB_LED_SHUTDOWN_N
R210  RESISTOR  330OHM 1%  pkg SMC_0402R_H016  page 10 : \1\ = FPGA_DONE ; \2\ = XP3R3V_FPGA

(kicad_pcb
	(version 20260206)
	(generator "pcbnew")
	(generator_version "10.0")
	(general
		(thickness 1.6)
		(legacy_teardrops no)
	)
	(paper "A4")
	(title_block
		(title "timecard-production-celestica-r4006 — R4006-B0001-02_R01.brd")
		(comment 1 "Time Appliance Project (Time Card) / footprints 793-794 of 1113")
	)
	(layers
		(0 "F.Cu" signal "TOP")
		(4 "In1.Cu" signal "L02_GND1")
		(6 "In2.Cu" signal "L03_SIG1")
		(8 "In3.Cu" signal "L04_GND2")
		(10 "In4.Cu" signal "L05_VCC1")
		(12 "In5.Cu" signal "L06_VCC2")
		(14 "In6.Cu" signal "L07_GND3")
		(16 "In7.Cu" signal "L08_SIG2")
		(18 "In8.Cu" signal "L09_GND4")
		(2 "B.Cu" signal "BOTTOM")
		(9 "F.Adhes" user "F.Adhesive")
		(11 "B.Adhes" user "B.Adhesive")
		(13 "F.Paste" user "Package Geometry/Pastemask Top")
		(15 "B.Paste" user "Package Geometry/Pastemask Bottom")
		(5 "F.SilkS" user "Ref Des/Silkscreen Top")
		(7 "B.SilkS" user "Ref Des/Silkscreen Bottom")
		(1 "F.Mask" user "Board Geometry/Soldermask Top")
		(3 "B.Mask" user "Board Geometry/Soldermask Bottom")
		(17 "Dwgs.User" user "User.Drawings")
		(19 "Cmts.User" user "User.Comments")
		(21 "Eco1.User" user "User.Eco1")
		(23 "Eco2.User" user "User.Eco2")
		(25 "Edge.Cuts" user "Board Geometry/Outline")
		(27 "Margin" user)
		(31 "F.CrtYd" user "Package Geometry/Place Bound Top")
		(29 "B.CrtYd" user "Package Geometry/Place Bound Bottom")
		(35 "F.Fab" user "Ref Des/Assembly Top")
		(33 "B.Fab" user "Ref Des/Assembly Bottom")
	)
	(footprint ""
		(layer "B.Cu")
		(at 133.9342 -106.172254 -90)
		(property "Reference" "R210"
			(at 7.747254 -1.15443 270)
			(unlocked yes)
			(layer "B.SilkS")
			(effects
				(font
					(size 0.7874 0.5842)
					(thickness 0.1524)
				)
				(justify mirror)
			)
		)
		(property "Value" "VAL*"
			(at -0.02032 2.13233 270)
			(unlocked yes)
			(layer "B.Fab")
			(hide yes)
			(effects
				(font
					(size 0.7874 0.5842)
					(thickness 0.1524)
				)
				(justify mirror)
			)
		)
		(property "Device Type" "RESISTOR-G155-13300-01,330OHM,A"
			(at -0.008382 1.210564 270)
			(unlocked yes)
			(layer "B.Fab")
			(hide yes)
			(effects
				(font
					(size 0.7874 0.5842)
					(thickness 0.1524)
				)
				(justify mirror)
			)
		)
		(property "User Part Number" "PARTNUM*"
			(at -0.02032 4.024884 270)
			(unlocked yes)
			(layer "Cmts.User")
			(hide yes)
			(effects
				(font
					(size 0.7874 0.5842)
					(thickness 0.1524)
				)
				(justify mirror)
			)
		)
		(property "Tolerance" "TOL*"
			(at -0.044704 3.05435 270)
			(unlocked yes)
			(layer "Cmts.User")
			(hide yes)
			(effects
				(font
					(size 0.7874 0.5842)
					(thickness 0.1524)
				)
				(justify mirror)
			)
		)
		(duplicate_pad_numbers_are_jumpers no)
		(fp_line
			(start -1.143 0.5588)
			(end -1.143 -0.5588)
			(stroke
				(width 0.1)
				(type default)
			)
			(layer "B.SilkS")
		)
		(fp_line
			(start 1.143 0.5588)
			(end -1.143 0.5588)
			(stroke
				(width 0.1)
				(type default)
			)
			(layer "B.SilkS")
		)
		(fp_line
			(start -1.143 -0.5588)
			(end 1.143 -0.5588)
			(stroke
				(width 0.1)
				(type default)
			)
			(layer "B.SilkS")
		)
		(fp_line
			(start 1.143 -0.5588)
			(end 1.143 0.5588)
			(stroke
				(width 0.1)
				(type default)
			)
			(layer "B.SilkS")
		)
		(fp_rect
			(start 1.143 0.5588)
			(end -1.143 -0.5588)
			(stroke
				(width 0)
				(type default)
			)
			(fill no)
			(layer "B.CrtYd")
		)
		(fp_line
			(start -0.508 0.3048)
			(end -0.508 -0.3048)
			(stroke
				(width 0.1)
				(type default)
			)
			(layer "B.Fab")
		)
		(fp_line
			(start 0.508 0.3048)
			(end -0.508 0.3048)
			(stroke
				(width 0.1)
				(type default)
			)
			(layer "B.Fab")
		)
		(fp_line
			(start -0.508 -0.3048)
			(end 0.508 -0.3048)
			(stroke
				(width 0.1)
				(type default)
			)
			(layer "B.Fab")
		)
		(fp_line
			(start 0.508 -0.3048)
			(end 0.508 0.3048)
			(stroke
				(width 0.1)
				(type default)
			)
			(layer "B.Fab")
		)
		(pad "1" smd rect
			(at 0.5334 0 90)
			(size 0.7112 0.6096)
			(layers "B.Cu" "B.Mask" "B.Paste")
			(net "FPGA_DONE")
		)
		(pad "2" smd rect
			(at -0.5334 0 90)
			(size 0.7112 0.6096)
			(layers "B.Cu" "B.Mask" "B.Paste")
			(net "XP3R3V_FPGA")
		)
		(zone
			(layer "B.Cu")
			(hatch none 0.5)
			(connect_pads
				(clearance 0)
			)
			(min_thickness 0.25)
			(keepout
				(tracks allowed)
				(vias not_allowed)
				(pads allowed)
				(copperpour not_allowed)
				(footprints allowed)
			)
			(placement
				(enabled no)
				(sheetname "")
			)
			(fill
				(thermal_gap 0.5)
				(thermal_bridge_width 0.5)
				(island_removal_mode 0)
			)
			(polygon
				(pts
					(xy 133.6294 -106.096054) (xy 134.239 -106.096054) (xy 134.239 -106.248454) (xy 133.6294 -106.248454)
				)
			)
		)
	)
	(footprint ""
		(layer "B.Cu")
		(at 111.125 -98.171)
		(property "Reference" "R319"
			(at 0.254 1.81737 0)
			(unlocked yes)
			(layer "B.SilkS")
			(effects
				(font
					(size 0.7874 0.5842)
					(thickness 0.1524)
				)
				(justify mirror)
			)
		)
		(property "Value" "VAL*"
			(at -0.02032 2.13233 0)
			(unlocked yes)
			(layer "B.Fab")
			(hide yes)
			(effects
				(font
					(size 0.7874 0.5842)
					(thickness 0.1524)
				)
				(justify mirror)
			)
		)
		(property "Tolerance" "TOL*"
			(at -0.044704 3.05435 0)
			(unlocked yes)
			(layer "Cmts.User")
			(hide yes)
			(effects
				(font
					(size 0.7874 0.5842)
					(thickness 0.1524)
				)
				(justify mirror)
			)
		)
		(property "User Part Number" "PARTNUM*"
			(at -0.02032 4.024884 0)
			(unlocked yes)
			(layer "Cmts.User")
			(hide yes)
			(effects
				(font
					(size 0.7874 0.5842)
					(thickness 0.1524)
				)
				(justify mirror)
			)
		)
		(property "Device Type" "RESISTOR-G155-133R0-01,33OHM,1%"
			(at -0.008382 1.210564 0)
			(unlocked yes)
			(layer "B.Fab")
			(hide yes)
			(effects
				(font
					(size 0.7874 0.5842)
					(thickness 0.1524)
				)
				(justify mirror)
			)
		)
		(duplicate_pad_numbers_are_jumpers no)
		(fp_line
			(start -1.143 -0.5588)
			(end 1.143 -0.5588)
			(stroke
				(width 0.1)
				(type default)
			)
			(layer "B.SilkS")
		)
		(fp_line
			(start -1.143 0.5588)
			(end -1.143 -0.5588)
			(stroke
				(width 0.1)
				(type default)
			)
			(layer "B.SilkS")
		)
		(fp_line
			(start 1.143 -0.5588)
			(end 1.143 0.5588)
			(stroke
				(width 0.1)
				(type default)
			)
			(layer "B.SilkS")
		)
		(fp_line
			(start 1.143 0.5588)
			(end -1.143 0.5588)
			(stroke
				(width 0.1)
				(type default)
			)
			(layer "B.SilkS")
		)
		(fp_poly
			(pts
				(xy 1.143 0.5588) (xy -1.143 0.5588) (xy -1.143 -0.5588) (xy 1.143 -0.5588)
			)
			(stroke
				(width 0)
				(type default)
			)
			(fill no)
			(layer "B.CrtYd")
		)
		(fp_line
			(start -0.508 -0.3048)
			(end 0.508 -0.3048)
			(stroke
				(width 0.1)
				(type default)
			)
			(layer "B.Fab")
		)
		(fp_line
			(start -0.508 0.3048)
			(end -0.508 -0.3048)
			(stroke
				(width 0.1)
				(type default)
			)
			(layer "B.Fab")
		)
		(fp_line
			(start 0.508 -0.3048)
			(end 0.508 0.3048)
			(stroke
				(width 0.1)
				(type default)
			)
			(layer "B.Fab")
		)
		(fp_line
			(start 0.508 0.3048)
			(end -0.508 0.3048)
			(stroke
				(width 0.1)
				(type default)
			)
			(layer "B.Fab")
		)
		(pad "1" smd rect
			(at 0.5334 0 180)
			(size 0.7112 0.6096)
			(layers "B.Cu" "B.Mask" "B.Paste")
			(net "FPGA_OUT_RGB_LED_SHUTDOWN_N")
		)
		(pad "2" smd rect
			(at -0.5334 0 180)
			(size 0.7112 0.6096)
			(layers "B.Cu" "B.Mask" "B.Paste")
			(net "RGB_LED_SHUTDOWN_N")
		)
		(zone
			(layer "B.Cu")
			(hatch none 0.5)
			(connect_pads
				(clearance 0)
			)
			(min_thickness 0.25)
			(keepout
				(tracks allowed)
				(vias not_allowed)
				(pads allowed)
				(copperpour not_allowed)
				(footprints allowed)
			)
			(placement
				(enabled no)
				(sheetname "")
			)
			(fill
				(thermal_gap 0.5)
				(thermal_bridge_width 0.5)
				(island_removal_mode 0)
			)
			(polygon
				(pts
					(xy 111.2012 -97.8662) (xy 111.2012 -98.4758) (xy 111.0488 -98.4758) (xy 111.0488 -97.8662)
				)
			)
		)
		(zone
			(layer "B.Cu")
			(hatch none 0.5)
			(connect_pads
				(clearance 0)
			)
			(min_thickness 0.25)
			(keepout
				(tracks not_allowed)
				(vias allowed)
				(pads allowed)
				(copperpour not_allowed)
				(footprints allowed)
			)
			(placement
				(enabled no)
				(sheetname "")
			)
			(fill
				(thermal_gap 0.5)
				(thermal_bridge_width 0.5)
				(island_removal_mode 0)
			)
			(polygon
				(pts
					(xy 111.2012 -97.8662) (xy 111.2012 -98.4758) (xy 111.0488 -98.4758) (xy 111.0488 -97.8662)
				)
			)
		)
	)
)
